FILE_TYPE = CONNECTIVITY;
{Allegro Design Entry HDL 17.2-2016 S081 (4005846) 1/11/2022}
"PAGE_NUMBER" = 30;
0"NC";
1"P5E_CPU0_PE3_TX_DP<15:0>";
2"P5E_CPU0_PE3_TX_DN<15:0>";
3"P5E_CPU0_PE3_RX_DP<15:0>";
4"P5E_CPU0_PE3_RX_DN<15:0>";
5"P5E_CPU0_PE2_TX_DP<15:0>";
6"P5E_CPU0_PE2_TX_DN<15:0>";
7"P5E_CPU0_PE2_RX_DP<15:0>";
8"P5E_CPU0_PE2_RX_DN<15:0>";
9"P5E_CPU0_PE2_RX_DN<15>";
10"P5E_CPU0_PE2_RX_DN<14>";
11"P5E_CPU0_PE2_RX_DN<13>";
12"P5E_CPU0_PE2_RX_DN<12>";
13"P5E_CPU0_PE2_RX_DN<11>";
14"P5E_CPU0_PE2_RX_DN<10>";
15"P5E_CPU0_PE2_RX_DN<9>";
16"P5E_CPU0_PE2_RX_DN<8>";
17"P5E_CPU0_PE2_RX_DN<7>";
18"P5E_CPU0_PE2_RX_DN<6>";
19"P5E_CPU0_PE2_RX_DN<5>";
20"P5E_CPU0_PE2_RX_DN<4>";
21"P5E_CPU0_PE2_RX_DN<3>";
22"P5E_CPU0_PE2_RX_DN<2>";
23"P5E_CPU0_PE2_RX_DN<1>";
24"P5E_CPU0_PE2_RX_DN<0>";
25"P5E_CPU0_PE2_RX_DP<15>";
26"P5E_CPU0_PE2_RX_DP<14>";
27"P5E_CPU0_PE2_RX_DP<13>";
28"P5E_CPU0_PE2_RX_DP<12>";
29"P5E_CPU0_PE2_RX_DP<11>";
30"P5E_CPU0_PE2_RX_DP<10>";
31"P5E_CPU0_PE2_RX_DP<9>";
32"P5E_CPU0_PE2_RX_DP<8>";
33"P5E_CPU0_PE2_RX_DP<7>";
34"P5E_CPU0_PE2_RX_DP<6>";
35"P5E_CPU0_PE2_RX_DP<5>";
36"P5E_CPU0_PE2_RX_DP<4>";
37"P5E_CPU0_PE2_RX_DP<3>";
38"P5E_CPU0_PE2_RX_DP<2>";
39"P5E_CPU0_PE2_RX_DP<1>";
40"P5E_CPU0_PE2_RX_DP<0>";
41"P5E_CPU0_PE2_TX_DN<15>";
42"P5E_CPU0_PE2_TX_DN<14>";
43"P5E_CPU0_PE2_TX_DN<13>";
44"P5E_CPU0_PE2_TX_DN<12>";
45"P5E_CPU0_PE2_TX_DN<11>";
46"P5E_CPU0_PE2_TX_DN<10>";
47"P5E_CPU0_PE2_TX_DN<9>";
48"P5E_CPU0_PE2_TX_DN<8>";
49"P5E_CPU0_PE2_TX_DN<7>";
50"P5E_CPU0_PE2_TX_DN<6>";
51"P5E_CPU0_PE2_TX_DN<5>";
52"P5E_CPU0_PE2_TX_DN<4>";
53"P5E_CPU0_PE2_TX_DN<3>";
54"P5E_CPU0_PE2_TX_DN<2>";
55"P5E_CPU0_PE2_TX_DN<1>";
56"P5E_CPU0_PE2_TX_DN<0>";
57"P5E_CPU0_PE2_TX_DP<15>";
58"P5E_CPU0_PE2_TX_DP<14>";
59"P5E_CPU0_PE2_TX_DP<13>";
60"P5E_CPU0_PE2_TX_DP<12>";
61"P5E_CPU0_PE2_TX_DP<11>";
62"P5E_CPU0_PE2_TX_DP<10>";
63"P5E_CPU0_PE2_TX_DP<9>";
64"P5E_CPU0_PE2_TX_DP<8>";
65"P5E_CPU0_PE2_TX_DP<7>";
66"P5E_CPU0_PE2_TX_DP<6>";
67"P5E_CPU0_PE2_TX_DP<5>";
68"P5E_CPU0_PE2_TX_DP<4>";
69"P5E_CPU0_PE2_TX_DP<3>";
70"P5E_CPU0_PE2_TX_DP<2>";
71"P5E_CPU0_PE2_TX_DP<1>";
72"P5E_CPU0_PE2_TX_DP<0>";
73"P5E_CPU0_PE3_RX_DN<15>";
74"P5E_CPU0_PE3_RX_DN<14>";
75"P5E_CPU0_PE3_RX_DN<13>";
76"P5E_CPU0_PE3_RX_DN<12>";
77"P5E_CPU0_PE3_RX_DN<11>";
78"P5E_CPU0_PE3_RX_DN<10>";
79"P5E_CPU0_PE3_RX_DN<9>";
80"P5E_CPU0_PE3_RX_DN<8>";
81"P5E_CPU0_PE3_RX_DN<7>";
82"P5E_CPU0_PE3_RX_DN<6>";
83"P5E_CPU0_PE3_RX_DN<5>";
84"P5E_CPU0_PE3_RX_DN<4>";
85"P5E_CPU0_PE3_RX_DN<3>";
86"P5E_CPU0_PE3_RX_DN<2>";
87"P5E_CPU0_PE3_RX_DN<1>";
88"P5E_CPU0_PE3_RX_DN<0>";
89"P5E_CPU0_PE3_RX_DP<15>";
90"P5E_CPU0_PE3_RX_DP<14>";
91"P5E_CPU0_PE3_RX_DP<13>";
92"P5E_CPU0_PE3_RX_DP<12>";
93"P5E_CPU0_PE3_RX_DP<11>";
94"P5E_CPU0_PE3_RX_DP<10>";
95"P5E_CPU0_PE3_RX_DP<9>";
96"P5E_CPU0_PE3_RX_DP<8>";
97"P5E_CPU0_PE3_RX_DP<7>";
98"P5E_CPU0_PE3_RX_DP<6>";
99"P5E_CPU0_PE3_RX_DP<5>";
100"P5E_CPU0_PE3_RX_DP<4>";
101"P5E_CPU0_PE3_RX_DP<3>";
102"P5E_CPU0_PE3_RX_DP<2>";
103"P5E_CPU0_PE3_RX_DP<1>";
104"P5E_CPU0_PE3_RX_DP<0>";
105"P5E_CPU0_PE3_TX_DN<15>";
106"P5E_CPU0_PE3_TX_DN<14>";
107"P5E_CPU0_PE3_TX_DN<13>";
108"P5E_CPU0_PE3_TX_DN<12>";
109"P5E_CPU0_PE3_TX_DN<11>";
110"P5E_CPU0_PE3_TX_DN<10>";
111"P5E_CPU0_PE3_TX_DN<9>";
112"P5E_CPU0_PE3_TX_DN<8>";
113"P5E_CPU0_PE3_TX_DN<7>";
114"P5E_CPU0_PE3_TX_DN<6>";
115"P5E_CPU0_PE3_TX_DN<5>";
116"P5E_CPU0_PE3_TX_DN<4>";
117"P5E_CPU0_PE3_TX_DN<3>";
118"P5E_CPU0_PE3_TX_DN<2>";
119"P5E_CPU0_PE3_TX_DN<1>";
120"P5E_CPU0_PE3_TX_DN<0>";
121"P5E_CPU0_PE3_TX_DP<15>";
122"P5E_CPU0_PE3_TX_DP<14>";
123"P5E_CPU0_PE3_TX_DP<13>";
124"P5E_CPU0_PE3_TX_DP<12>";
125"P5E_CPU0_PE3_TX_DP<11>";
126"P5E_CPU0_PE3_TX_DP<10>";
127"P5E_CPU0_PE3_TX_DP<9>";
128"P5E_CPU0_PE3_TX_DP<8>";
129"P5E_CPU0_PE3_TX_DP<7>";
130"P5E_CPU0_PE3_TX_DP<6>";
131"P5E_CPU0_PE3_TX_DP<5>";
132"P5E_CPU0_PE3_TX_DP<4>";
133"P5E_CPU0_PE3_TX_DP<3>";
134"P5E_CPU0_PE3_TX_DP<2>";
135"P5E_CPU0_PE3_TX_DP<1>";
136"P5E_CPU0_PE3_TX_DP<0>";
%"SOCKET4677_AZIF0045P001C01CS"
"19","(1100,3025)","0","pure_quanta","I139";
;
PART_NUMBER"DGA^7000023"
VALUE"SOCKET4677_AZIF0045-P001C01CS"
MATERIAL"IO"
PART_TYPE"SMLF"
$LOCATION"U2"
CDS_LMAN_SYM_OUTLINE"-1050,950,1050,-950"
NEEDS_NO_SIZE"TRUE"
CDS_LIB"pure_quanta"
CDS_LOCATION"U2"
$SEC"19"
CDS_SEC"19";
"PE2_TX_DP0"
$PN"CT14"72;
"PE2_TX_DP1"
$PN"CW15"71;
"PE2_TX_DP2"
$PN"CY14"70;
"PE2_TX_DP3"
$PN"DC15"69;
"PE2_TX_DP4"
$PN"DD14"68;
"PE2_TX_DP5"
$PN"DG15"67;
"PE2_TX_DP6"
$PN"DH14"66;
"PE2_TX_DP7"
$PN"DL15"65;
"PE2_TX_DP8"
$PN"DM14"64;
"PE2_TX_DP9"
$PN"DR15"63;
"PE2_TX_DP10"
$PN"DT14"62;
"PE2_TX_DP11"
$PN"DW15"61;
"PE2_TX_DP12"
$PN"DY14"60;
"PE2_TX_DP13"
$PN"EC15"59;
"PE2_TX_DP14"
$PN"ED14"58;
"PE2_TX_DP15"
$PN"EG15"57;
"PE2_TX_DN0"
$PN"CU13"56;
"PE2_TX_DN1"
$PN"CV14"55;
"PE2_TX_DN2"
$PN"DA13"54;
"PE2_TX_DN3"
$PN"DB14"53;
"PE2_TX_DN4"
$PN"DE13"52;
"PE2_TX_DN5"
$PN"DF14"51;
"PE2_TX_DN6"
$PN"DJ13"50;
"PE2_TX_DN7"
$PN"DK14"49;
"PE2_TX_DN8"
$PN"DN13"48;
"PE2_TX_DN9"
$PN"DP14"47;
"PE2_TX_DN10"
$PN"DU13"46;
"PE2_TX_DN11"
$PN"DV14"45;
"PE2_TX_DN12"
$PN"EA13"44;
"PE2_TX_DN13"
$PN"EB14"43;
"PE2_TX_DN14"
$PN"EE13"42;
"PE2_TX_DN15"
$PN"EF14"41;
"PE2_RX_DP0"
$PN"CV10"40;
"PE2_RX_DP1"
$PN"CW11"39;
"PE2_RX_DP2"
$PN"DB10"38;
"PE2_RX_DP3"
$PN"DC11"37;
"PE2_RX_DP4"
$PN"DF10"36;
"PE2_RX_DP5"
$PN"DG11"35;
"PE2_RX_DP6"
$PN"DK10"34;
"PE2_RX_DP7"
$PN"DL11"33;
"PE2_RX_DP8"
$PN"DP10"32;
"PE2_RX_DP9"
$PN"DR11"31;
"PE2_RX_DP10"
$PN"DV10"30;
"PE2_RX_DP11"
$PN"DW11"29;
"PE2_RX_DP12"
$PN"EB10"28;
"PE2_RX_DP13"
$PN"EC11"27;
"PE2_RX_DP14"
$PN"EF10"26;
"PE2_RX_DP15"
$PN"EG11"25;
"PE2_RX_DN0"
$PN"CU9"24;
"PE2_RX_DN1"
$PN"CY10"23;
"PE2_RX_DN2"
$PN"DA9"22;
"PE2_RX_DN3"
$PN"DD10"21;
"PE2_RX_DN4"
$PN"DE9"20;
"PE2_RX_DN5"
$PN"DH10"19;
"PE2_RX_DN6"
$PN"DJ9"18;
"PE2_RX_DN7"
$PN"DM10"17;
"PE2_RX_DN8"
$PN"DN9"16;
"PE2_RX_DN9"
$PN"DT10"15;
"PE2_RX_DN10"
$PN"DU9"14;
"PE2_RX_DN11"
$PN"DY10"13;
"PE2_RX_DN12"
$PN"EA9"12;
"PE2_RX_DN13"
$PN"ED10"11;
"PE2_RX_DN14"
$PN"EE9"10;
"PE2_RX_DN15"
$PN"EH10"9;
%"SOCKET4677_AZIF0045P001C01CS"
"20","(1100,250)","0","pure_quanta","I140";
;
PART_NUMBER"DGA^7000023"
VALUE"SOCKET4677_AZIF0045-P001C01CS"
MATERIAL"IO"
PART_TYPE"SMLF"
$LOCATION"U2"
CDS_LMAN_SYM_OUTLINE"-1050,950,1050,-950"
NEEDS_NO_SIZE"TRUE"
CDS_LIB"pure_quanta"
CDS_LOCATION"U2"
$SEC"20"
CDS_SEC"20";
"PE3_TX_DP0"
$PN"ED87"136;
"PE3_TX_DP1"
$PN"EC86"135;
"PE3_TX_DP2"
$PN"EA86"134;
"PE3_TX_DP3"
$PN"DW86"133;
"PE3_TX_DP4"
$PN"DU86"132;
"PE3_TX_DP5"
$PN"DR86"131;
"PE3_TX_DP6"
$PN"DN86"130;
"PE3_TX_DP7"
$PN"DL86"129;
"PE3_TX_DP8"
$PN"DJ86"128;
"PE3_TX_DP9"
$PN"DG86"127;
"PE3_TX_DP10"
$PN"DE86"126;
"PE3_TX_DP11"
$PN"DC86"125;
"PE3_TX_DP12"
$PN"DA86"124;
"PE3_TX_DP13"
$PN"CW86"123;
"PE3_TX_DP14"
$PN"CU86"122;
"PE3_TX_DP15"
$PN"CR86"121;
"PE3_TX_DN0"
$PN"EE86"120;
"PE3_TX_DN1"
$PN"EB85"119;
"PE3_TX_DN2"
$PN"DY87"118;
"PE3_TX_DN3"
$PN"DV85"117;
"PE3_TX_DN4"
$PN"DT87"116;
"PE3_TX_DN5"
$PN"DP85"115;
"PE3_TX_DN6"
$PN"DM87"114;
"PE3_TX_DN7"
$PN"DK85"113;
"PE3_TX_DN8"
$PN"DH87"112;
"PE3_TX_DN9"
$PN"DF85"111;
"PE3_TX_DN10"
$PN"DD87"110;
"PE3_TX_DN11"
$PN"DB85"109;
"PE3_TX_DN12"
$PN"CY87"108;
"PE3_TX_DN13"
$PN"CV85"107;
"PE3_TX_DN14"
$PN"CT87"106;
"PE3_TX_DN15"
$PN"CP85"105;
"PE3_RX_DP0"
$PN"EJ90"104;
"PE3_RX_DP1"
$PN"EE90"103;
"PE3_RX_DP2"
$PN"EB89"102;
"PE3_RX_DP3"
$PN"EA90"101;
"PE3_RX_DP4"
$PN"DW90"100;
"PE3_RX_DP5"
$PN"DT91"99;
"PE3_RX_DP6"
$PN"DR90"98;
"PE3_RX_DP7"
$PN"DM91"97;
"PE3_RX_DP8"
$PN"DK89"96;
"PE3_RX_DP9"
$PN"DJ90"95;
"PE3_RX_DP10"
$PN"DF89"94;
"PE3_RX_DP11"
$PN"DE90"93;
"PE3_RX_DP12"
$PN"DC90"92;
"PE3_RX_DP13"
$PN"CY91"91;
"PE3_RX_DP14"
$PN"CW90"90;
"PE3_RX_DP15"
$PN"CT91"89;
"PE3_RX_DN0"
$PN"EH89"88;
"PE3_RX_DN1"
$PN"ED91"87;
"PE3_RX_DN2"
$PN"EC90"86;
"PE3_RX_DN3"
$PN"DY91"85;
"PE3_RX_DN4"
$PN"DV89"84;
"PE3_RX_DN5"
$PN"DU90"83;
"PE3_RX_DN6"
$PN"DP89"82;
"PE3_RX_DN7"
$PN"DN90"81;
"PE3_RX_DN8"
$PN"DL90"80;
"PE3_RX_DN9"
$PN"DH91"79;
"PE3_RX_DN10"
$PN"DG90"78;
"PE3_RX_DN11"
$PN"DD91"77;
"PE3_RX_DN12"
$PN"DB89"76;
"PE3_RX_DN13"
$PN"DA90"75;
"PE3_RX_DN14"
$PN"CV89"74;
"PE3_RX_DN15"
$PN"CU90"73;
%"TAP"
"1","(-575,-550)","2","standard","I253";
;
CDS_LIB"standard"
BODY_TYPE"PLUMBING"
HDL_TAP"TRUE";
"B \NAC \NWC"4;
"S \NAC"
BN"0"88;
%"TAP"
"1","(-575,-450)","2","standard","I254";
;
CDS_LIB"standard"
BODY_TYPE"PLUMBING"
HDL_TAP"TRUE";
"B \NAC \NWC"4;
"S \NAC"
BN"2"86;
%"TAP"
"1","(-575,-500)","2","standard","I255";
;
CDS_LIB"standard"
BODY_TYPE"PLUMBING"
HDL_TAP"TRUE";
"B \NAC \NWC"4;
"S \NAC"
BN"1"87;
%"TAP"
"1","(-575,-400)","2","standard","I256";
;
CDS_LIB"standard"
BODY_TYPE"PLUMBING"
HDL_TAP"TRUE";
"B \NAC \NWC"4;
"S \NAC"
BN"3"85;
%"TAP"
"1","(-575,-350)","2","standard","I257";
;
CDS_LIB"standard"
BODY_TYPE"PLUMBING"
HDL_TAP"TRUE";
"B \NAC \NWC"4;
"S \NAC"
BN"4"84;
%"TAP"
"1","(-575,-300)","2","standard","I258";
;
CDS_LIB"standard"
BODY_TYPE"PLUMBING"
HDL_TAP"TRUE";
"B \NAC \NWC"4;
"S \NAC"
BN"5"83;
%"TAP"
"1","(-575,-200)","2","standard","I259";
;
CDS_LIB"standard"
BODY_TYPE"PLUMBING"
HDL_TAP"TRUE";
"B \NAC \NWC"4;
"S \NAC"
BN"7"81;
%"TAP"
"1","(-575,-250)","2","standard","I260";
;
CDS_LIB"standard"
BODY_TYPE"PLUMBING"
HDL_TAP"TRUE";
"B \NAC \NWC"4;
"S \NAC"
BN"6"82;
%"TAP"
"1","(-575,-150)","2","standard","I261";
;
CDS_LIB"standard"
BODY_TYPE"PLUMBING"
HDL_TAP"TRUE";
"B \NAC \NWC"4;
"S \NAC"
BN"8"80;
%"TAP"
"1","(-575,-100)","2","standard","I262";
;
CDS_LIB"standard"
BODY_TYPE"PLUMBING"
HDL_TAP"TRUE";
"B \NAC \NWC"4;
"S \NAC"
BN"9"79;
%"TAP"
"1","(-575,-50)","2","standard","I263";
;
CDS_LIB"standard"
BODY_TYPE"PLUMBING"
HDL_TAP"TRUE";
"B \NAC \NWC"4;
"S \NAC"
BN"10"78;
%"TAP"
"1","(-575,0)","2","standard","I264";
;
CDS_LIB"standard"
BODY_TYPE"PLUMBING"
HDL_TAP"TRUE";
"B \NAC \NWC"4;
"S \NAC"
BN"11"77;
%"TAP"
"1","(-575,50)","2","standard","I265";
;
CDS_LIB"standard"
BODY_TYPE"PLUMBING"
HDL_TAP"TRUE";
"B \NAC \NWC"4;
"S \NAC"
BN"12"76;
%"TAP"
"1","(-575,150)","2","standard","I266";
;
CDS_LIB"standard"
BODY_TYPE"PLUMBING"
HDL_TAP"TRUE";
"B \NAC \NWC"4;
"S \NAC"
BN"14"74;
%"TAP"
"1","(-575,100)","2","standard","I267";
;
CDS_LIB"standard"
BODY_TYPE"PLUMBING"
HDL_TAP"TRUE";
"B \NAC \NWC"4;
"S \NAC"
BN"13"75;
%"TAP"
"1","(-575,200)","2","standard","I268";
;
CDS_LIB"standard"
BODY_TYPE"PLUMBING"
HDL_TAP"TRUE";
"B \NAC \NWC"4;
"S \NAC"
BN"15"73;
%"TAP"
"1","(-575,300)","2","standard","I269";
;
CDS_LIB"standard"
BODY_TYPE"PLUMBING"
HDL_TAP"TRUE";
"B \NAC \NWC"3;
"S \NAC"
BN"0"104;
%"TAP"
"1","(-575,350)","2","standard","I270";
;
CDS_LIB"standard"
BODY_TYPE"PLUMBING"
HDL_TAP"TRUE";
"B \NAC \NWC"3;
"S \NAC"
BN"1"103;
%"TAP"
"1","(-575,450)","2","standard","I271";
;
CDS_LIB"standard"
BODY_TYPE"PLUMBING"
HDL_TAP"TRUE";
"B \NAC \NWC"3;
"S \NAC"
BN"3"101;
%"TAP"
"1","(-575,400)","2","standard","I272";
;
CDS_LIB"standard"
BODY_TYPE"PLUMBING"
HDL_TAP"TRUE";
"B \NAC \NWC"3;
"S \NAC"
BN"2"102;
%"TAP"
"1","(-575,500)","2","standard","I273";
;
CDS_LIB"standard"
BODY_TYPE"PLUMBING"
HDL_TAP"TRUE";
"B \NAC \NWC"3;
"S \NAC"
BN"4"100;
%"TAP"
"1","(-575,550)","2","standard","I274";
;
CDS_LIB"standard"
BODY_TYPE"PLUMBING"
HDL_TAP"TRUE";
"B \NAC \NWC"3;
"S \NAC"
BN"5"99;
%"TAP"
"1","(-575,600)","2","standard","I275";
;
CDS_LIB"standard"
BODY_TYPE"PLUMBING"
HDL_TAP"TRUE";
"B \NAC \NWC"3;
"S \NAC"
BN"6"98;
%"TAP"
"1","(-575,700)","2","standard","I276";
;
CDS_LIB"standard"
BODY_TYPE"PLUMBING"
HDL_TAP"TRUE";
"B \NAC \NWC"3;
"S \NAC"
BN"8"96;
%"TAP"
"1","(-575,650)","2","standard","I277";
;
CDS_LIB"standard"
BODY_TYPE"PLUMBING"
HDL_TAP"TRUE";
"B \NAC \NWC"3;
"S \NAC"
BN"7"97;
%"TAP"
"1","(-575,750)","2","standard","I278";
;
CDS_LIB"standard"
BODY_TYPE"PLUMBING"
HDL_TAP"TRUE";
"B \NAC \NWC"3;
"S \NAC"
BN"9"95;
%"TAP"
"1","(-575,800)","2","standard","I279";
;
CDS_LIB"standard"
BODY_TYPE"PLUMBING"
HDL_TAP"TRUE";
"B \NAC \NWC"3;
"S \NAC"
BN"10"94;
%"TAP"
"1","(-575,850)","2","standard","I280";
;
CDS_LIB"standard"
BODY_TYPE"PLUMBING"
HDL_TAP"TRUE";
"B \NAC \NWC"3;
"S \NAC"
BN"11"93;
%"TAP"
"1","(-575,900)","2","standard","I281";
;
CDS_LIB"standard"
BODY_TYPE"PLUMBING"
HDL_TAP"TRUE";
"B \NAC \NWC"3;
"S \NAC"
BN"12"92;
%"TAP"
"1","(-575,950)","2","standard","I282";
;
CDS_LIB"standard"
BODY_TYPE"PLUMBING"
HDL_TAP"TRUE";
"B \NAC \NWC"3;
"S \NAC"
BN"13"91;
%"TAP"
"1","(-575,1000)","2","standard","I283";
;
CDS_LIB"standard"
BODY_TYPE"PLUMBING"
HDL_TAP"TRUE";
"B \NAC \NWC"3;
"S \NAC"
BN"14"90;
%"TAP"
"1","(-575,1050)","2","standard","I284";
;
CDS_LIB"standard"
BODY_TYPE"PLUMBING"
HDL_TAP"TRUE";
"B \NAC \NWC"3;
"S \NAC"
BN"15"89;
%"TAP"
"1","(2825,-550)","0","standard","I285";
;
CDS_LIB"standard"
BODY_TYPE"PLUMBING"
HDL_TAP"TRUE";
"B \NAC \NWC"2;
"S \NAC"
BN"0"120;
%"TAP"
"1","(2825,-500)","0","standard","I286";
;
CDS_LIB"standard"
BODY_TYPE"PLUMBING"
HDL_TAP"TRUE";
"B \NAC \NWC"2;
"S \NAC"
BN"1"119;
%"TAP"
"1","(2825,-400)","0","standard","I287";
;
CDS_LIB"standard"
BODY_TYPE"PLUMBING"
HDL_TAP"TRUE";
"B \NAC \NWC"2;
"S \NAC"
BN"3"117;
%"TAP"
"1","(2825,-450)","0","standard","I288";
;
CDS_LIB"standard"
BODY_TYPE"PLUMBING"
HDL_TAP"TRUE";
"B \NAC \NWC"2;
"S \NAC"
BN"2"118;
%"TAP"
"1","(2825,-350)","0","standard","I289";
;
CDS_LIB"standard"
BODY_TYPE"PLUMBING"
HDL_TAP"TRUE";
"B \NAC \NWC"2;
"S \NAC"
BN"4"116;
%"TAP"
"1","(2825,-250)","0","standard","I290";
;
CDS_LIB"standard"
BODY_TYPE"PLUMBING"
HDL_TAP"TRUE";
"B \NAC \NWC"2;
"S \NAC"
BN"6"114;
%"TAP"
"1","(2825,-300)","0","standard","I291";
;
CDS_LIB"standard"
BODY_TYPE"PLUMBING"
HDL_TAP"TRUE";
"B \NAC \NWC"2;
"S \NAC"
BN"5"115;
%"TAP"
"1","(2825,-150)","0","standard","I292";
;
CDS_LIB"standard"
BODY_TYPE"PLUMBING"
HDL_TAP"TRUE";
"B \NAC \NWC"2;
"S \NAC"
BN"8"112;
%"TAP"
"1","(2825,-200)","0","standard","I293";
;
CDS_LIB"standard"
BODY_TYPE"PLUMBING"
HDL_TAP"TRUE";
"B \NAC \NWC"2;
"S \NAC"
BN"7"113;
%"TAP"
"1","(2825,-100)","0","standard","I294";
;
CDS_LIB"standard"
BODY_TYPE"PLUMBING"
HDL_TAP"TRUE";
"B \NAC \NWC"2;
"S \NAC"
BN"9"111;
%"TAP"
"1","(2825,-50)","0","standard","I295";
;
CDS_LIB"standard"
BODY_TYPE"PLUMBING"
HDL_TAP"TRUE";
"B \NAC \NWC"2;
"S \NAC"
BN"10"110;
%"TAP"
"1","(2825,0)","0","standard","I296";
;
CDS_LIB"standard"
BODY_TYPE"PLUMBING"
HDL_TAP"TRUE";
"B \NAC \NWC"2;
"S \NAC"
BN"11"109;
%"TAP"
"1","(2825,50)","0","standard","I297";
;
CDS_LIB"standard"
BODY_TYPE"PLUMBING"
HDL_TAP"TRUE";
"B \NAC \NWC"2;
"S \NAC"
BN"12"108;
%"TAP"
"1","(2825,100)","0","standard","I298";
;
CDS_LIB"standard"
BODY_TYPE"PLUMBING"
HDL_TAP"TRUE";
"B \NAC \NWC"2;
"S \NAC"
BN"13"107;
%"TAP"
"1","(2825,150)","0","standard","I299";
;
CDS_LIB"standard"
BODY_TYPE"PLUMBING"
HDL_TAP"TRUE";
"B \NAC \NWC"2;
"S \NAC"
BN"14"106;
%"TAP"
"1","(2825,200)","0","standard","I300";
;
CDS_LIB"standard"
BODY_TYPE"PLUMBING"
HDL_TAP"TRUE";
"B \NAC \NWC"2;
"S \NAC"
BN"15"105;
%"TAP"
"1","(2825,300)","0","standard","I301";
;
CDS_LIB"standard"
BODY_TYPE"PLUMBING"
HDL_TAP"TRUE";
"B \NAC \NWC"1;
"S \NAC"
BN"0"136;
%"TAP"
"1","(2825,350)","0","standard","I302";
;
CDS_LIB"standard"
BODY_TYPE"PLUMBING"
HDL_TAP"TRUE";
"B \NAC \NWC"1;
"S \NAC"
BN"1"135;
%"TAP"
"1","(2825,400)","0","standard","I303";
;
CDS_LIB"standard"
BODY_TYPE"PLUMBING"
HDL_TAP"TRUE";
"B \NAC \NWC"1;
"S \NAC"
BN"2"134;
%"TAP"
"1","(2825,500)","0","standard","I304";
;
CDS_LIB"standard"
BODY_TYPE"PLUMBING"
HDL_TAP"TRUE";
"B \NAC \NWC"1;
"S \NAC"
BN"4"132;
%"TAP"
"1","(2825,450)","0","standard","I305";
;
CDS_LIB"standard"
BODY_TYPE"PLUMBING"
HDL_TAP"TRUE";
"B \NAC \NWC"1;
"S \NAC"
BN"3"133;
%"TAP"
"1","(2825,550)","0","standard","I306";
;
CDS_LIB"standard"
BODY_TYPE"PLUMBING"
HDL_TAP"TRUE";
"B \NAC \NWC"1;
"S \NAC"
BN"5"131;
%"TAP"
"1","(2825,600)","0","standard","I307";
;
CDS_LIB"standard"
BODY_TYPE"PLUMBING"
HDL_TAP"TRUE";
"B \NAC \NWC"1;
"S \NAC"
BN"6"130;
%"TAP"
"1","(2825,650)","0","standard","I308";
;
CDS_LIB"standard"
BODY_TYPE"PLUMBING"
HDL_TAP"TRUE";
"B \NAC \NWC"1;
"S \NAC"
BN"7"129;
%"TAP"
"1","(2825,750)","0","standard","I309";
;
CDS_LIB"standard"
BODY_TYPE"PLUMBING"
HDL_TAP"TRUE";
"B \NAC \NWC"1;
"S \NAC"
BN"9"127;
%"TAP"
"1","(2825,700)","0","standard","I310";
;
CDS_LIB"standard"
BODY_TYPE"PLUMBING"
HDL_TAP"TRUE";
"B \NAC \NWC"1;
"S \NAC"
BN"8"128;
%"TAP"
"1","(2825,800)","0","standard","I311";
;
CDS_LIB"standard"
BODY_TYPE"PLUMBING"
HDL_TAP"TRUE";
"B \NAC \NWC"1;
"S \NAC"
BN"10"126;
%"TAP"
"1","(2825,900)","0","standard","I312";
;
CDS_LIB"standard"
BODY_TYPE"PLUMBING"
HDL_TAP"TRUE";
"B \NAC \NWC"1;
"S \NAC"
BN"12"124;
%"TAP"
"1","(2825,850)","0","standard","I313";
;
CDS_LIB"standard"
BODY_TYPE"PLUMBING"
HDL_TAP"TRUE";
"B \NAC \NWC"1;
"S \NAC"
BN"11"125;
%"TAP"
"1","(2825,1000)","0","standard","I314";
;
CDS_LIB"standard"
BODY_TYPE"PLUMBING"
HDL_TAP"TRUE";
"B \NAC \NWC"1;
"S \NAC"
BN"14"122;
%"TAP"
"1","(2825,950)","0","standard","I315";
;
CDS_LIB"standard"
BODY_TYPE"PLUMBING"
HDL_TAP"TRUE";
"B \NAC \NWC"1;
"S \NAC"
BN"13"123;
%"TAP"
"1","(2825,1050)","0","standard","I316";
;
CDS_LIB"standard"
BODY_TYPE"PLUMBING"
HDL_TAP"TRUE";
"B \NAC \NWC"1;
"S \NAC"
BN"15"121;
%"TAP"
"1","(2825,2225)","0","standard","I319";
;
CDS_LIB"standard"
BODY_TYPE"PLUMBING"
HDL_TAP"TRUE";
"B \NAC \NWC"6;
"S \NAC"
BN"0"56;
%"TAP"
"1","(2825,2275)","0","standard","I320";
;
CDS_LIB"standard"
BODY_TYPE"PLUMBING"
HDL_TAP"TRUE";
"B \NAC \NWC"6;
"S \NAC"
BN"1"55;
%"TAP"
"1","(2825,2375)","0","standard","I321";
;
CDS_LIB"standard"
BODY_TYPE"PLUMBING"
HDL_TAP"TRUE";
"B \NAC \NWC"6;
"S \NAC"
BN"3"53;
%"TAP"
"1","(2825,2325)","0","standard","I322";
;
CDS_LIB"standard"
BODY_TYPE"PLUMBING"
HDL_TAP"TRUE";
"B \NAC \NWC"6;
"S \NAC"
BN"2"54;
%"TAP"
"1","(2825,2425)","0","standard","I323";
;
CDS_LIB"standard"
BODY_TYPE"PLUMBING"
HDL_TAP"TRUE";
"B \NAC \NWC"6;
"S \NAC"
BN"4"52;
%"TAP"
"1","(2825,2525)","0","standard","I324";
;
CDS_LIB"standard"
BODY_TYPE"PLUMBING"
HDL_TAP"TRUE";
"B \NAC \NWC"6;
"S \NAC"
BN"6"50;
%"TAP"
"1","(2825,2475)","0","standard","I325";
;
CDS_LIB"standard"
BODY_TYPE"PLUMBING"
HDL_TAP"TRUE";
"B \NAC \NWC"6;
"S \NAC"
BN"5"51;
%"TAP"
"1","(2825,2625)","0","standard","I326";
;
CDS_LIB"standard"
BODY_TYPE"PLUMBING"
HDL_TAP"TRUE";
"B \NAC \NWC"6;
"S \NAC"
BN"8"48;
%"TAP"
"1","(2825,2575)","0","standard","I327";
;
CDS_LIB"standard"
BODY_TYPE"PLUMBING"
HDL_TAP"TRUE";
"B \NAC \NWC"6;
"S \NAC"
BN"7"49;
%"TAP"
"1","(2825,2675)","0","standard","I328";
;
CDS_LIB"standard"
BODY_TYPE"PLUMBING"
HDL_TAP"TRUE";
"B \NAC \NWC"6;
"S \NAC"
BN"9"47;
%"TAP"
"1","(2825,2725)","0","standard","I329";
;
CDS_LIB"standard"
BODY_TYPE"PLUMBING"
HDL_TAP"TRUE";
"B \NAC \NWC"6;
"S \NAC"
BN"10"46;
%"TAP"
"1","(2825,2775)","0","standard","I330";
;
CDS_LIB"standard"
BODY_TYPE"PLUMBING"
HDL_TAP"TRUE";
"B \NAC \NWC"6;
"S \NAC"
BN"11"45;
%"TAP"
"1","(2825,2825)","0","standard","I331";
;
CDS_LIB"standard"
BODY_TYPE"PLUMBING"
HDL_TAP"TRUE";
"B \NAC \NWC"6;
"S \NAC"
BN"12"44;
%"TAP"
"1","(2825,2875)","0","standard","I332";
;
CDS_LIB"standard"
BODY_TYPE"PLUMBING"
HDL_TAP"TRUE";
"B \NAC \NWC"6;
"S \NAC"
BN"13"43;
%"TAP"
"1","(2825,2925)","0","standard","I333";
;
CDS_LIB"standard"
BODY_TYPE"PLUMBING"
HDL_TAP"TRUE";
"B \NAC \NWC"6;
"S \NAC"
BN"14"42;
%"TAP"
"1","(2825,2975)","0","standard","I334";
;
CDS_LIB"standard"
BODY_TYPE"PLUMBING"
HDL_TAP"TRUE";
"B \NAC \NWC"6;
"S \NAC"
BN"15"41;
%"TAP"
"1","(2825,3075)","0","standard","I335";
;
CDS_LIB"standard"
BODY_TYPE"PLUMBING"
HDL_TAP"TRUE";
"B \NAC \NWC"5;
"S \NAC"
BN"0"72;
%"TAP"
"1","(2825,3125)","0","standard","I336";
;
CDS_LIB"standard"
BODY_TYPE"PLUMBING"
HDL_TAP"TRUE";
"B \NAC \NWC"5;
"S \NAC"
BN"1"71;
%"TAP"
"1","(2825,3175)","0","standard","I337";
;
CDS_LIB"standard"
BODY_TYPE"PLUMBING"
HDL_TAP"TRUE";
"B \NAC \NWC"5;
"S \NAC"
BN"2"70;
%"TAP"
"1","(2825,3275)","0","standard","I338";
;
CDS_LIB"standard"
BODY_TYPE"PLUMBING"
HDL_TAP"TRUE";
"B \NAC \NWC"5;
"S \NAC"
BN"4"68;
%"TAP"
"1","(2825,3225)","0","standard","I339";
;
CDS_LIB"standard"
BODY_TYPE"PLUMBING"
HDL_TAP"TRUE";
"B \NAC \NWC"5;
"S \NAC"
BN"3"69;
%"TAP"
"1","(2825,3325)","0","standard","I340";
;
CDS_LIB"standard"
BODY_TYPE"PLUMBING"
HDL_TAP"TRUE";
"B \NAC \NWC"5;
"S \NAC"
BN"5"67;
%"TAP"
"1","(2825,3375)","0","standard","I341";
;
CDS_LIB"standard"
BODY_TYPE"PLUMBING"
HDL_TAP"TRUE";
"B \NAC \NWC"5;
"S \NAC"
BN"6"66;
%"TAP"
"1","(2825,3425)","0","standard","I342";
;
CDS_LIB"standard"
BODY_TYPE"PLUMBING"
HDL_TAP"TRUE";
"B \NAC \NWC"5;
"S \NAC"
BN"7"65;
%"TAP"
"1","(2825,3525)","0","standard","I343";
;
CDS_LIB"standard"
BODY_TYPE"PLUMBING"
HDL_TAP"TRUE";
"B \NAC \NWC"5;
"S \NAC"
BN"9"63;
%"TAP"
"1","(2825,3475)","0","standard","I344";
;
CDS_LIB"standard"
BODY_TYPE"PLUMBING"
HDL_TAP"TRUE";
"B \NAC \NWC"5;
"S \NAC"
BN"8"64;
%"TAP"
"1","(2825,3575)","0","standard","I345";
;
CDS_LIB"standard"
BODY_TYPE"PLUMBING"
HDL_TAP"TRUE";
"B \NAC \NWC"5;
"S \NAC"
BN"10"62;
%"TAP"
"1","(2825,3675)","0","standard","I346";
;
CDS_LIB"standard"
BODY_TYPE"PLUMBING"
HDL_TAP"TRUE";
"B \NAC \NWC"5;
"S \NAC"
BN"12"60;
%"TAP"
"1","(2825,3625)","0","standard","I347";
;
CDS_LIB"standard"
BODY_TYPE"PLUMBING"
HDL_TAP"TRUE";
"B \NAC \NWC"5;
"S \NAC"
BN"11"61;
%"TAP"
"1","(2825,3775)","0","standard","I348";
;
CDS_LIB"standard"
BODY_TYPE"PLUMBING"
HDL_TAP"TRUE";
"B \NAC \NWC"5;
"S \NAC"
BN"14"58;
%"TAP"
"1","(2825,3725)","0","standard","I349";
;
CDS_LIB"standard"
BODY_TYPE"PLUMBING"
HDL_TAP"TRUE";
"B \NAC \NWC"5;
"S \NAC"
BN"13"59;
%"TAP"
"1","(2825,3825)","0","standard","I350";
;
CDS_LIB"standard"
BODY_TYPE"PLUMBING"
HDL_TAP"TRUE";
"B \NAC \NWC"5;
"S \NAC"
BN"15"57;
%"TAP"
"1","(-600,2225)","2","standard","I37";
;
CDS_LIB"standard"
BODY_TYPE"PLUMBING"
HDL_TAP"TRUE";
"B \NAC \NWC"8;
"S \NAC"
BN"0"24;
%"TAP"
"1","(-600,2275)","2","standard","I38";
;
CDS_LIB"standard"
BODY_TYPE"PLUMBING"
HDL_TAP"TRUE";
"B \NAC \NWC"8;
"S \NAC"
BN"1"23;
%"TAP"
"1","(-600,2325)","2","standard","I39";
;
CDS_LIB"standard"
BODY_TYPE"PLUMBING"
HDL_TAP"TRUE";
"B \NAC \NWC"8;
"S \NAC"
BN"2"22;
%"TAP"
"1","(-600,2475)","2","standard","I40";
;
CDS_LIB"standard"
BODY_TYPE"PLUMBING"
HDL_TAP"TRUE";
"B \NAC \NWC"8;
"S \NAC"
BN"5"19;
%"TAP"
"1","(-600,2425)","2","standard","I41";
;
CDS_LIB"standard"
BODY_TYPE"PLUMBING"
HDL_TAP"TRUE";
"B \NAC \NWC"8;
"S \NAC"
BN"4"20;
%"TAP"
"1","(-600,2375)","2","standard","I42";
;
CDS_LIB"standard"
BODY_TYPE"PLUMBING"
HDL_TAP"TRUE";
"B \NAC \NWC"8;
"S \NAC"
BN"3"21;
%"TAP"
"1","(-600,2575)","2","standard","I43";
;
CDS_LIB"standard"
BODY_TYPE"PLUMBING"
HDL_TAP"TRUE";
"B \NAC \NWC"8;
"S \NAC"
BN"7"17;
%"TAP"
"1","(-600,2525)","2","standard","I44";
;
CDS_LIB"standard"
BODY_TYPE"PLUMBING"
HDL_TAP"TRUE";
"B \NAC \NWC"8;
"S \NAC"
BN"6"18;
%"TAP"
"1","(-600,2725)","2","standard","I45";
;
CDS_LIB"standard"
BODY_TYPE"PLUMBING"
HDL_TAP"TRUE";
"B \NAC \NWC"8;
"S \NAC"
BN"10"14;
%"TAP"
"1","(-600,2625)","2","standard","I46";
;
CDS_LIB"standard"
BODY_TYPE"PLUMBING"
HDL_TAP"TRUE";
"B \NAC \NWC"8;
"S \NAC"
BN"8"16;
%"TAP"
"1","(-600,2675)","2","standard","I47";
;
CDS_LIB"standard"
BODY_TYPE"PLUMBING"
HDL_TAP"TRUE";
"B \NAC \NWC"8;
"S \NAC"
BN"9"15;
%"TAP"
"1","(-600,2775)","2","standard","I48";
;
CDS_LIB"standard"
BODY_TYPE"PLUMBING"
HDL_TAP"TRUE";
"B \NAC \NWC"8;
"S \NAC"
BN"11"13;
%"TAP"
"1","(-600,2825)","2","standard","I49";
;
CDS_LIB"standard"
BODY_TYPE"PLUMBING"
HDL_TAP"TRUE";
"B \NAC \NWC"8;
"S \NAC"
BN"12"12;
%"TAP"
"1","(-600,2925)","2","standard","I50";
;
CDS_LIB"standard"
BODY_TYPE"PLUMBING"
HDL_TAP"TRUE";
"B \NAC \NWC"8;
"S \NAC"
BN"14"10;
%"TAP"
"1","(-600,2975)","2","standard","I51";
;
CDS_LIB"standard"
BODY_TYPE"PLUMBING"
HDL_TAP"TRUE";
"B \NAC \NWC"8;
"S \NAC"
BN"15"9;
%"TAP"
"1","(-600,2875)","2","standard","I52";
;
CDS_LIB"standard"
BODY_TYPE"PLUMBING"
HDL_TAP"TRUE";
"B \NAC \NWC"8;
"S \NAC"
BN"13"11;
%"TAP"
"1","(-600,3075)","2","standard","I53";
;
CDS_LIB"standard"
BODY_TYPE"PLUMBING"
HDL_TAP"TRUE";
"B \NAC \NWC"7;
"S \NAC"
BN"0"40;
%"TAP"
"1","(-600,3125)","2","standard","I54";
;
CDS_LIB"standard"
BODY_TYPE"PLUMBING"
HDL_TAP"TRUE";
"B \NAC \NWC"7;
"S \NAC"
BN"1"39;
%"TAP"
"1","(-600,3175)","2","standard","I55";
;
CDS_LIB"standard"
BODY_TYPE"PLUMBING"
HDL_TAP"TRUE";
"B \NAC \NWC"7;
"S \NAC"
BN"2"38;
%"TAP"
"1","(-600,3225)","2","standard","I56";
;
CDS_LIB"standard"
BODY_TYPE"PLUMBING"
HDL_TAP"TRUE";
"B \NAC \NWC"7;
"S \NAC"
BN"3"37;
%"TAP"
"1","(-600,3375)","2","standard","I57";
;
CDS_LIB"standard"
BODY_TYPE"PLUMBING"
HDL_TAP"TRUE";
"B \NAC \NWC"7;
"S \NAC"
BN"6"34;
%"TAP"
"1","(-600,3325)","2","standard","I58";
;
CDS_LIB"standard"
BODY_TYPE"PLUMBING"
HDL_TAP"TRUE";
"B \NAC \NWC"7;
"S \NAC"
BN"5"35;
%"TAP"
"1","(-600,3275)","2","standard","I59";
;
CDS_LIB"standard"
BODY_TYPE"PLUMBING"
HDL_TAP"TRUE";
"B \NAC \NWC"7;
"S \NAC"
BN"4"36;
%"TAP"
"1","(-600,3475)","2","standard","I60";
;
CDS_LIB"standard"
BODY_TYPE"PLUMBING"
HDL_TAP"TRUE";
"B \NAC \NWC"7;
"S \NAC"
BN"8"32;
%"TAP"
"1","(-600,3425)","2","standard","I61";
;
CDS_LIB"standard"
BODY_TYPE"PLUMBING"
HDL_TAP"TRUE";
"B \NAC \NWC"7;
"S \NAC"
BN"7"33;
%"TAP"
"1","(-600,3625)","2","standard","I62";
;
CDS_LIB"standard"
BODY_TYPE"PLUMBING"
HDL_TAP"TRUE";
"B \NAC \NWC"7;
"S \NAC"
BN"11"29;
%"TAP"
"1","(-600,3525)","2","standard","I63";
;
CDS_LIB"standard"
BODY_TYPE"PLUMBING"
HDL_TAP"TRUE";
"B \NAC \NWC"7;
"S \NAC"
BN"9"31;
%"TAP"
"1","(-600,3575)","2","standard","I64";
;
CDS_LIB"standard"
BODY_TYPE"PLUMBING"
HDL_TAP"TRUE";
"B \NAC \NWC"7;
"S \NAC"
BN"10"30;
%"TAP"
"1","(-600,3675)","2","standard","I65";
;
CDS_LIB"standard"
BODY_TYPE"PLUMBING"
HDL_TAP"TRUE";
"B \NAC \NWC"7;
"S \NAC"
BN"12"28;
%"TAP"
"1","(-600,3725)","2","standard","I66";
;
CDS_LIB"standard"
BODY_TYPE"PLUMBING"
HDL_TAP"TRUE";
"B \NAC \NWC"7;
"S \NAC"
BN"13"27;
%"TAP"
"1","(-600,3825)","2","standard","I67";
;
CDS_LIB"standard"
BODY_TYPE"PLUMBING"
HDL_TAP"TRUE";
"B \NAC \NWC"7;
"S \NAC"
BN"15"25;
%"TAP"
"1","(-600,3775)","2","standard","I68";
;
CDS_LIB"standard"
BODY_TYPE"PLUMBING"
HDL_TAP"TRUE";
"B \NAC \NWC"7;
"S \NAC"
BN"14"26;
END.
